# T6G (Grand Teton) — schematic netlist excerpt (pin names and nets, part order shuffled) for the footprints in the layout excerpt that follows; sources: Cadence DE-HDL packaged netlist, KiCad conversion of 04192023_DAF0TMB3IC0_F0TG_MB_C_brd_V02_OCP.brd

R859  Q_RES  0 5% CHIP  pkg 0603LF  page 345 : A = P0V9_CPU1_RT2_2A_2D ; B = P0V9_CPU1_RT2_2A
C2672  Q_CAP  22UF 4V 20% X6S  pkg C0402  page 75 : A = PVDD18_S5_P1 ; B = GND

(kicad_pcb
	(version 20260206)
	(generator "pcbnew")
	(generator_version "10.0")
	(general
		(thickness 1.6)
		(legacy_teardrops no)
	)
	(paper "A4")
	(title_block
		(title "04192023_DAF0TMB3IC0_F0TG_MB_C_brd_V02_OCP.brd")
		(comment 1 "Grand Teton / footprints 5325-5326 of 8354")
	)
	(layers
		(0 "F.Cu" signal "TOP")
		(4 "In1.Cu" signal "GND")
		(6 "In2.Cu" signal "IN1")
		(8 "In3.Cu" signal "GND1")
		(10 "In4.Cu" signal "IN2")
		(12 "In5.Cu" signal "GND2")
		(14 "In6.Cu" signal "IN3")
		(16 "In7.Cu" signal "GND3")
		(18 "In8.Cu" signal "VCC")
		(20 "In9.Cu" signal "VCC1")
		(22 "In10.Cu" signal "GND4")
		(24 "In11.Cu" signal "IN4")
		(26 "In12.Cu" signal "GND5")
		(28 "In13.Cu" signal "IN5")
		(30 "In14.Cu" signal "GND6")
		(32 "In15.Cu" signal "IN6")
		(34 "In16.Cu" signal "GND7")
		(2 "B.Cu" signal "BOTTOM")
		(9 "F.Adhes" user "F.Adhesive")
		(11 "B.Adhes" user "B.Adhesive")
		(13 "F.Paste" user "Package Geometry/Pastemask Top")
		(15 "B.Paste" user "Package Geometry/Pastemask Bottom")
		(5 "F.SilkS" user "Ref Des/Silkscreen Top")
		(7 "B.SilkS" user "Ref Des/Silkscreen Bottom")
		(1 "F.Mask" user "Board Geometry/Soldermask Top")
		(3 "B.Mask" user "Board Geometry/Soldermask Bottom")
		(17 "Dwgs.User" user "User.Drawings")
		(19 "Cmts.User" user "User.Comments")
		(21 "Eco1.User" user "User.Eco1")
		(23 "Eco2.User" user "User.Eco2")
		(25 "Edge.Cuts" user "Board Geometry/Outline")
		(27 "Margin" user)
		(31 "F.CrtYd" user "Package Geometry/Place Bound Top")
		(29 "B.CrtYd" user "Package Geometry/Place Bound Bottom")
		(35 "F.Fab" user "Ref Des/Assembly Top")
		(33 "B.Fab" user "Ref Des/Assembly Bottom")
	)
	(footprint ""
		(layer "B.Cu")
		(at 99.128834 -254.067564 180)
		(property "Reference" "C2672"
			(at 0 0 0)
			(layer "B.SilkS")
			(hide yes)
			(effects
				(font
					(size 1.27 1.27)
				)
				(justify mirror)
			)
		)
		(property "Value" ""
			(at 0 0 0)
			(layer "B.Fab")
			(effects
				(font
					(size 1.27 1.27)
				)
				(justify mirror)
			)
		)
		(duplicate_pad_numbers_are_jumpers no)
		(fp_line
			(start 0.7874 0.4064)
			(end 0.7874 -0.4064)
			(stroke
				(width 0.1524)
				(type default)
			)
			(layer "B.SilkS")
		)
		(fp_line
			(start 0.7874 -0.4064)
			(end -0.7874 -0.4064)
			(stroke
				(width 0.1524)
				(type default)
			)
			(layer "B.SilkS")
		)
		(fp_line
			(start -0.7874 0.4064)
			(end 0.7874 0.4064)
			(stroke
				(width 0.1524)
				(type default)
			)
			(layer "B.SilkS")
		)
		(fp_line
			(start -0.7874 -0.4064)
			(end -0.7874 0.4064)
			(stroke
				(width 0.1524)
				(type default)
			)
			(layer "B.SilkS")
		)
		(fp_line
			(start 0.67945 0.3048)
			(end 0.67945 -0.305054)
			(stroke
				(width 0.1)
				(type default)
			)
			(layer "B.Fab")
		)
		(fp_line
			(start 0.67945 -0.305054)
			(end 0.12065 -0.305054)
			(stroke
				(width 0.1)
				(type default)
			)
			(layer "B.Fab")
		)
		(fp_line
			(start 0.12065 0.3048)
			(end 0.67945 0.3048)
			(stroke
				(width 0.1)
				(type default)
			)
			(layer "B.Fab")
		)
		(fp_line
			(start 0.12065 0.2794)
			(end 0.12065 0.3048)
			(stroke
				(width 0.1)
				(type default)
			)
			(layer "B.Fab")
		)
		(fp_line
			(start 0.12065 -0.2794)
			(end -0.12065 -0.2794)
			(stroke
				(width 0.1)
				(type default)
			)
			(layer "B.Fab")
		)
		(fp_line
			(start 0.12065 -0.305054)
			(end 0.12065 -0.2794)
			(stroke
				(width 0.1)
				(type default)
			)
			(layer "B.Fab")
		)
		(fp_line
			(start -0.120396 0.3048)
			(end -0.120396 0.2794)
			(stroke
				(width 0.1)
				(type default)
			)
			(layer "B.Fab")
		)
		(fp_line
			(start -0.120396 0.2794)
			(end 0.12065 0.2794)
			(stroke
				(width 0.1)
				(type default)
			)
			(layer "B.Fab")
		)
		(fp_line
			(start -0.12065 -0.2794)
			(end -0.12065 -0.3048)
			(stroke
				(width 0.1)
				(type default)
			)
			(layer "B.Fab")
		)
		(fp_line
			(start -0.12065 -0.3048)
			(end -0.67945 -0.3048)
			(stroke
				(width 0.1)
				(type default)
			)
			(layer "B.Fab")
		)
		(fp_line
			(start -0.67945 0.3048)
			(end -0.120396 0.3048)
			(stroke
				(width 0.1)
				(type default)
			)
			(layer "B.Fab")
		)
		(fp_line
			(start -0.67945 -0.3048)
			(end -0.67945 0.3048)
			(stroke
				(width 0.1)
				(type default)
			)
			(layer "B.Fab")
		)
		(pad "1" smd circle
			(at 0.40005 0)
			(size 0 0)
			(layers "B.Cu" "B.Mask" "B.Paste")
			(net "PVDD18_S5_P1")
		)
		(pad "2" smd circle
			(at -0.40005 0)
			(size 0 0)
			(layers "B.Cu" "B.Mask" "B.Paste")
			(net "GND")
		)
	)
	(footprint ""
		(layer "B.Cu")
		(at 140.989558 -393.242546 180)
		(property "Reference" "R859"
			(at 0 0 0)
			(layer "B.SilkS")
			(hide yes)
			(effects
				(font
					(size 1.27 1.27)
				)
				(justify mirror)
			)
		)
		(property "Value" ""
			(at 0 0 0)
			(layer "B.Fab")
			(effects
				(font
					(size 1.27 1.27)
				)
				(justify mirror)
			)
		)
		(duplicate_pad_numbers_are_jumpers no)
		(fp_line
			(start 1.2954 0.5842)
			(end 1.2954 -0.5842)
			(stroke
				(width 0.1524)
				(type default)
			)
			(layer "B.SilkS")
		)
		(fp_line
			(start 1.2954 -0.5842)
			(end -1.2954 -0.5842)
			(stroke
				(width 0.1524)
				(type default)
			)
			(layer "B.SilkS")
		)
		(fp_line
			(start -1.2954 0.5842)
			(end 1.2954 0.5842)
			(stroke
				(width 0.1524)
				(type default)
			)
			(layer "B.SilkS")
		)
		(fp_line
			(start -1.2954 -0.5842)
			(end -1.2954 0.5842)
			(stroke
				(width 0.1524)
				(type default)
			)
			(layer "B.SilkS")
		)
		(fp_line
			(start 1.1938 0.4064)
			(end 1.1938 -0.406654)
			(stroke
				(width 0.1)
				(type default)
			)
			(layer "B.Fab")
		)
		(fp_line
			(start 1.1938 -0.406654)
			(end 0.8636 -0.406654)
			(stroke
				(width 0.1)
				(type default)
			)
			(layer "B.Fab")
		)
		(fp_line
			(start 0.8636 0.4572)
			(end 0.8636 0.4318)
			(stroke
				(width 0.1)
				(type default)
			)
			(layer "B.Fab")
		)
		(fp_line
			(start 0.8636 0.4318)
			(end 0.8636 0.4064)
			(stroke
				(width 0.1)
				(type default)
			)
			(layer "B.Fab")
		)
		(fp_line
			(start 0.8636 0.4064)
			(end 1.1938 0.4064)
			(stroke
				(width 0.1)
				(type default)
			)
			(layer "B.Fab")
		)
		(fp_line
			(start 0.8636 -0.406654)
			(end 0.8636 -0.4572)
			(stroke
				(width 0.1)
				(type default)
			)
			(layer "B.Fab")
		)
		(fp_line
			(start 0.8636 -0.4572)
			(end -0.8636 -0.4572)
			(stroke
				(width 0.1)
				(type default)
			)
			(layer "B.Fab")
		)
		(fp_line
			(start -0.8636 0.4572)
			(end 0.8636 0.4572)
			(stroke
				(width 0.1)
				(type default)
			)
			(layer "B.Fab")
		)
		(fp_line
			(start -0.8636 0.4064)
			(end -0.8636 0.4572)
			(stroke
				(width 0.1)
				(type default)
			)
			(layer "B.Fab")
		)
		(fp_line
			(start -0.8636 -0.406654)
			(end -1.1938 -0.406654)
			(stroke
				(width 0.1)
				(type default)
			)
			(layer "B.Fab")
		)
		(fp_line
			(start -0.8636 -0.4572)
			(end -0.8636 -0.406654)
			(stroke
				(width 0.1)
				(type default)
			)
			(layer "B.Fab")
		)
		(fp_line
			(start -1.1938 0.4064)
			(end -0.8636 0.4064)
			(stroke
				(width 0.1)
				(type default)
			)
			(layer "B.Fab")
		)
		(fp_line
			(start -1.1938 -0.406654)
			(end -1.1938 0.4064)
			(stroke
				(width 0.1)
				(type default)
			)
			(layer "B.Fab")
		)
		(pad "1" smd rect
			(at 0.7366 0 90)
			(size 0.7112 0.8128)
			(layers "B.Cu" "B.Mask" "B.Paste")
			(net "P0V9_CPU1_RT2_2A_2D")
		)
		(pad "2" smd rect
			(at -0.7366 0 90)
			(size 0.7112 0.8128)
			(layers "B.Cu" "B.Mask" "B.Paste")
			(net "P0V9_CPU1_RT2_2A")
		)
	)
)
